# S9S_MB_2U (Grand Teton) — schematic parts with pin connectivity, parts 512–619 of 6093; source: Cadence DE-HDL packaged netlist (pstxprt.dat, pstxnet.dat, pstchip.dat)

C613  Q_CAP  1UF 25V 10% EMPTY  pkg C0402  page 130 : 1 = RST_PLD_CPU1_DRAM_GH_N ; 2 = GND
C614  Q_CAP  1UF 25V 10% EMPTY  pkg C0402  page 130 : 1 = RST_PLD_CPU1_DRAM_AB_N ; 2 = GND
C615  Q_CAP  1UF 25V 10% EMPTY  pkg C0402  page 130 : 1 = RST_PLD_CPU1_DRAM_CD_N ; 2 = GND
C616  Q_CAP  1UF 25V 10% EMPTY  pkg C0402  page 130 : 1 = RST_PLD_CPU1_DRAM_EF_N ; 2 = GND
C621  Q_CAP  1UF 25V 10% EMPTY  pkg C0402  page 129 : 1 = RST_PLD_CPU0_DRAM_GH_N ; 2 = GND
C622  Q_CAP  1UF 25V 10% EMPTY  pkg C0402  page 129 : 1 = RST_PLD_CPU0_DRAM_AB_N ; 2 = GND
C623  Q_CAP  1UF 25V 10% EMPTY  pkg C0402  page 129 : 1 = RST_PLD_CPU0_DRAM_CD_N ; 2 = GND
C624  Q_CAP  1UF 25V 10% EMPTY  pkg C0402  page 129 : 1 = RST_PLD_CPU0_DRAM_EF_N ; 2 = GND
C626  Q_CAP  1000PF 50V 5% EMPTY  pkg 0402  page 278 : 1 = PWRGD_PVCCD_HV_CPU0_R ; 2 = GND
C629  Q_CAP  0.1UF 25V 10% X7R  pkg 0402  page 243 : 1 = P3V3_AUX ; 2 = GND
C639  Q_CAP  0.1UF 25V 10% X7R  pkg 0402  page 154 : 1 = P3V3_AUX ; 2 = GND
C640  Q_CAP  0.1UF 25V 10% X7R  pkg 0402  page 154 : 1 = P3V3_AUX ; 2 = GND
C641  Q_CAP  0.1UF 25V 10% X7R  pkg 0402  page 154 : 1 = P3V3_AUX ; 2 = GND
C678  Q_CAP_DIFFBUS  DIFF BUS_0.22UF 6.3V 20% X6S  pkg C0201  page 177 : 1 = P5E_CPU1_PE4_TX_C_DN<15> ; 2 = P5E_CPU1_PE4_TX_DN<15>
C679  Q_CAP_DIFFBUS  DIFF BUS_0.22UF 6.3V 20% X6S  pkg C0201  page 177 : 1 = P5E_CPU1_PE4_TX_C_DP<15> ; 2 = P5E_CPU1_PE4_TX_DP<15>
C680  Q_CAP_DIFFBUS  DIFF BUS_0.22UF 6.3V 20% X6S  pkg C0201  page 177 : 1 = P5E_CPU1_PE4_TX_C_DN<14> ; 2 = P5E_CPU1_PE4_TX_DN<14>
C681  Q_CAP_DIFFBUS  DIFF BUS_0.22UF 6.3V 20% X6S  pkg C0201  page 177 : 1 = P5E_CPU1_PE4_TX_C_DP<14> ; 2 = P5E_CPU1_PE4_TX_DP<14>
C682  Q_CAP_DIFFBUS  DIFF BUS_0.22UF 6.3V 20% X6S  pkg C0201  page 177 : 1 = P5E_CPU1_PE4_TX_C_DN<13> ; 2 = P5E_CPU1_PE4_TX_DN<13>
C683  Q_CAP_DIFFBUS  DIFF BUS_0.22UF 6.3V 20% X6S  pkg C0201  page 177 : 1 = P5E_CPU1_PE4_TX_C_DP<13> ; 2 = P5E_CPU1_PE4_TX_DP<13>
C684  Q_CAP_DIFFBUS  DIFF BUS_0.22UF 6.3V 20% X6S  pkg C0201  page 177 : 1 = P5E_CPU1_PE4_TX_C_DN<12> ; 2 = P5E_CPU1_PE4_TX_DN<12>
C685  Q_CAP_DIFFBUS  DIFF BUS_0.22UF 6.3V 20% X6S  pkg C0201  page 177 : 1 = P5E_CPU1_PE4_TX_C_DP<12> ; 2 = P5E_CPU1_PE4_TX_DP<12>
C686  Q_CAP_DIFFBUS  DIFF BUS_0.22UF 6.3V 20% X6S  pkg C0201  page 177 : 1 = P5E_CPU1_PE4_TX_C_DN<11> ; 2 = P5E_CPU1_PE4_TX_DN<11>
C687  Q_CAP_DIFFBUS  DIFF BUS_0.22UF 6.3V 20% X6S  pkg C0201  page 177 : 1 = P5E_CPU1_PE4_TX_C_DP<11> ; 2 = P5E_CPU1_PE4_TX_DP<11>
C688  Q_CAP_DIFFBUS  DIFF BUS_0.22UF 6.3V 20% X6S  pkg C0201  page 177 : 1 = P5E_CPU1_PE4_TX_C_DN<10> ; 2 = P5E_CPU1_PE4_TX_DN<10>
C689  Q_CAP_DIFFBUS  DIFF BUS_0.22UF 6.3V 20% X6S  pkg C0201  page 177 : 1 = P5E_CPU1_PE4_TX_C_DP<10> ; 2 = P5E_CPU1_PE4_TX_DP<10>
C690  Q_CAP_DIFFBUS  DIFF BUS_0.22UF 6.3V 20% X6S  pkg C0201  page 177 : 1 = P5E_CPU1_PE4_TX_C_DN<9> ; 2 = P5E_CPU1_PE4_TX_DN<9>
C691  Q_CAP_DIFFBUS  DIFF BUS_0.22UF 6.3V 20% X6S  pkg C0201  page 177 : 1 = P5E_CPU1_PE4_TX_C_DP<9> ; 2 = P5E_CPU1_PE4_TX_DP<9>
C692  Q_CAP_DIFFBUS  DIFF BUS_0.22UF 6.3V 20% X6S  pkg C0201  page 177 : 1 = P5E_CPU1_PE4_TX_C_DN<8> ; 2 = P5E_CPU1_PE4_TX_DN<8>
C693  Q_CAP_DIFFBUS  DIFF BUS_0.22UF 6.3V 20% X6S  pkg C0201  page 177 : 1 = P5E_CPU1_PE4_TX_C_DP<8> ; 2 = P5E_CPU1_PE4_TX_DP<8>
C694  Q_CAP_DIFFBUS  DIFF BUS_0.22UF 6.3V 20% X6S  pkg C0201  page 177 : 1 = P5E_CPU1_PE4_TX_C_DN<7> ; 2 = P5E_CPU1_PE4_TX_DN<7>
C695  Q_CAP_DIFFBUS  DIFF BUS_0.22UF 6.3V 20% X6S  pkg C0201  page 177 : 1 = P5E_CPU1_PE4_TX_C_DP<7> ; 2 = P5E_CPU1_PE4_TX_DP<7>
C696  Q_CAP_DIFFBUS  DIFF BUS_0.22UF 6.3V 20% X6S  pkg C0201  page 177 : 1 = P5E_CPU1_PE4_TX_C_DN<6> ; 2 = P5E_CPU1_PE4_TX_DN<6>
C697  Q_CAP_DIFFBUS  DIFF BUS_0.22UF 6.3V 20% X6S  pkg C0201  page 177 : 1 = P5E_CPU1_PE4_TX_C_DP<6> ; 2 = P5E_CPU1_PE4_TX_DP<6>
C698  Q_CAP_DIFFBUS  DIFF BUS_0.22UF 6.3V 20% X6S  pkg C0201  page 177 : 1 = P5E_CPU1_PE4_TX_C_DN<5> ; 2 = P5E_CPU1_PE4_TX_DN<5>
C699  Q_CAP_DIFFBUS  DIFF BUS_0.22UF 6.3V 20% X6S  pkg C0201  page 177 : 1 = P5E_CPU1_PE4_TX_C_DP<5> ; 2 = P5E_CPU1_PE4_TX_DP<5>
C700  Q_CAP_DIFFBUS  DIFF BUS_0.22UF 6.3V 20% X6S  pkg C0201  page 177 : 1 = P5E_CPU1_PE4_TX_C_DN<4> ; 2 = P5E_CPU1_PE4_TX_DN<4>
C701  Q_CAP_DIFFBUS  DIFF BUS_0.22UF 6.3V 20% X6S  pkg C0201  page 177 : 1 = P5E_CPU1_PE4_TX_C_DP<4> ; 2 = P5E_CPU1_PE4_TX_DP<4>
C702  Q_CAP_DIFFBUS  DIFF BUS_0.22UF 6.3V 20% X6S  pkg C0201  page 177 : 1 = P5E_CPU1_PE4_TX_C_DN<3> ; 2 = P5E_CPU1_PE4_TX_DN<3>
C703  Q_CAP_DIFFBUS  DIFF BUS_0.22UF 6.3V 20% X6S  pkg C0201  page 177 : 1 = P5E_CPU1_PE4_TX_C_DP<3> ; 2 = P5E_CPU1_PE4_TX_DP<3>
C704  Q_CAP_DIFFBUS  DIFF BUS_0.22UF 6.3V 20% X6S  pkg C0201  page 177 : 1 = P5E_CPU1_PE4_TX_C_DN<2> ; 2 = P5E_CPU1_PE4_TX_DN<2>
C705  Q_CAP_DIFFBUS  DIFF BUS_0.22UF 6.3V 20% X6S  pkg C0201  page 177 : 1 = P5E_CPU1_PE4_TX_C_DP<2> ; 2 = P5E_CPU1_PE4_TX_DP<2>
C706  Q_CAP_DIFFBUS  DIFF BUS_0.22UF 6.3V 20% X6S  pkg C0201  page 177 : 1 = P5E_CPU1_PE4_TX_C_DN<1> ; 2 = P5E_CPU1_PE4_TX_DN<1>
C707  Q_CAP_DIFFBUS  DIFF BUS_0.22UF 6.3V 20% X6S  pkg C0201  page 177 : 1 = P5E_CPU1_PE4_TX_C_DP<1> ; 2 = P5E_CPU1_PE4_TX_DP<1>
C708  Q_CAP_DIFFBUS  DIFF BUS_0.22UF 6.3V 20% X6S  pkg C0201  page 177 : 1 = P5E_CPU1_PE4_TX_C_DN<0> ; 2 = P5E_CPU1_PE4_TX_DN<0>
C709  Q_CAP_DIFFBUS  DIFF BUS_0.22UF 6.3V 20% X6S  pkg C0201  page 177 : 1 = P5E_CPU1_PE4_TX_C_DP<0> ; 2 = P5E_CPU1_PE4_TX_DP<0>
C710  Q_CAP_DIFFBUS  DIFF BUS_0.22UF 6.3V 20% X6S  pkg C0201  page 176 : 1 = P5E_CPU1_PE0_TX_C_DN<15> ; 2 = P5E_CPU1_PE0_TX_DN<15>
C711  Q_CAP_DIFFBUS  DIFF BUS_0.22UF 6.3V 20% X6S  pkg C0201  page 176 : 1 = P5E_CPU1_PE0_TX_C_DP<15> ; 2 = P5E_CPU1_PE0_TX_DP<15>
C712  Q_CAP_DIFFBUS  DIFF BUS_0.22UF 6.3V 20% X6S  pkg C0201  page 176 : 1 = P5E_CPU1_PE0_TX_C_DN<14> ; 2 = P5E_CPU1_PE0_TX_DN<14>
C713  Q_CAP_DIFFBUS  DIFF BUS_0.22UF 6.3V 20% X6S  pkg C0201  page 176 : 1 = P5E_CPU1_PE0_TX_C_DP<14> ; 2 = P5E_CPU1_PE0_TX_DP<14>
C714  Q_CAP_DIFFBUS  DIFF BUS_0.22UF 6.3V 20% X6S  pkg C0201  page 176 : 1 = P5E_CPU1_PE0_TX_C_DN<13> ; 2 = P5E_CPU1_PE0_TX_DN<13>
C715  Q_CAP_DIFFBUS  DIFF BUS_0.22UF 6.3V 20% X6S  pkg C0201  page 176 : 1 = P5E_CPU1_PE0_TX_C_DP<13> ; 2 = P5E_CPU1_PE0_TX_DP<13>
C716  Q_CAP_DIFFBUS  DIFF BUS_0.22UF 6.3V 20% X6S  pkg C0201  page 176 : 1 = P5E_CPU1_PE0_TX_C_DN<12> ; 2 = P5E_CPU1_PE0_TX_DN<12>
C717  Q_CAP_DIFFBUS  DIFF BUS_0.22UF 6.3V 20% X6S  pkg C0201  page 176 : 1 = P5E_CPU1_PE0_TX_C_DP<12> ; 2 = P5E_CPU1_PE0_TX_DP<12>
C718  Q_CAP_DIFFBUS  DIFF BUS_0.22UF 6.3V 20% X6S  pkg C0201  page 176 : 1 = P5E_CPU1_PE0_TX_C_DN<11> ; 2 = P5E_CPU1_PE0_TX_DN<11>
C719  Q_CAP_DIFFBUS  DIFF BUS_0.22UF 6.3V 20% X6S  pkg C0201  page 176 : 1 = P5E_CPU1_PE0_TX_C_DP<11> ; 2 = P5E_CPU1_PE0_TX_DP<11>
C720  Q_CAP_DIFFBUS  DIFF BUS_0.22UF 6.3V 20% X6S  pkg C0201  page 176 : 1 = P5E_CPU1_PE0_TX_C_DN<10> ; 2 = P5E_CPU1_PE0_TX_DN<10>
C721  Q_CAP_DIFFBUS  DIFF BUS_0.22UF 6.3V 20% X6S  pkg C0201  page 176 : 1 = P5E_CPU1_PE0_TX_C_DP<10> ; 2 = P5E_CPU1_PE0_TX_DP<10>
C722  Q_CAP_DIFFBUS  DIFF BUS_0.22UF 6.3V 20% X6S  pkg C0201  page 176 : 1 = P5E_CPU1_PE0_TX_C_DN<9> ; 2 = P5E_CPU1_PE0_TX_DN<9>
C723  Q_CAP_DIFFBUS  DIFF BUS_0.22UF 6.3V 20% X6S  pkg C0201  page 176 : 1 = P5E_CPU1_PE0_TX_C_DP<9> ; 2 = P5E_CPU1_PE0_TX_DP<9>
C724  Q_CAP_DIFFBUS  DIFF BUS_0.22UF 6.3V 20% X6S  pkg C0201  page 176 : 1 = P5E_CPU1_PE0_TX_C_DN<8> ; 2 = P5E_CPU1_PE0_TX_DN<8>
C725  Q_CAP_DIFFBUS  DIFF BUS_0.22UF 6.3V 20% X6S  pkg C0201  page 176 : 1 = P5E_CPU1_PE0_TX_C_DP<8> ; 2 = P5E_CPU1_PE0_TX_DP<8>
C726  Q_CAP_DIFFBUS  DIFF BUS_0.22UF 6.3V 20% X6S  pkg C0201  page 176 : 1 = P5E_CPU1_PE0_TX_C_DN<7> ; 2 = P5E_CPU1_PE0_TX_DN<7>
C727  Q_CAP_DIFFBUS  DIFF BUS_0.22UF 6.3V 20% X6S  pkg C0201  page 176 : 1 = P5E_CPU1_PE0_TX_C_DP<7> ; 2 = P5E_CPU1_PE0_TX_DP<7>
C728  Q_CAP_DIFFBUS  DIFF BUS_0.22UF 6.3V 20% X6S  pkg C0201  page 176 : 1 = P5E_CPU1_PE0_TX_C_DN<6> ; 2 = P5E_CPU1_PE0_TX_DN<6>
C729  Q_CAP_DIFFBUS  DIFF BUS_0.22UF 6.3V 20% X6S  pkg C0201  page 176 : 1 = P5E_CPU1_PE0_TX_C_DP<6> ; 2 = P5E_CPU1_PE0_TX_DP<6>
C730  Q_CAP_DIFFBUS  DIFF BUS_0.22UF 6.3V 20% X6S  pkg C0201  page 176 : 1 = P5E_CPU1_PE0_TX_C_DN<5> ; 2 = P5E_CPU1_PE0_TX_DN<5>
C731  Q_CAP_DIFFBUS  DIFF BUS_0.22UF 6.3V 20% X6S  pkg C0201  page 176 : 1 = P5E_CPU1_PE0_TX_C_DP<5> ; 2 = P5E_CPU1_PE0_TX_DP<5>
C732  Q_CAP_DIFFBUS  DIFF BUS_0.22UF 6.3V 20% X6S  pkg C0201  page 176 : 1 = P5E_CPU1_PE0_TX_C_DN<4> ; 2 = P5E_CPU1_PE0_TX_DN<4>
C733  Q_CAP_DIFFBUS  DIFF BUS_0.22UF 6.3V 20% X6S  pkg C0201  page 176 : 1 = P5E_CPU1_PE0_TX_C_DP<4> ; 2 = P5E_CPU1_PE0_TX_DP<4>
C734  Q_CAP_DIFFBUS  DIFF BUS_0.22UF 6.3V 20% X6S  pkg C0201  page 176 : 1 = P5E_CPU1_PE0_TX_C_DN<3> ; 2 = P5E_CPU1_PE0_TX_DN<3>
C735  Q_CAP_DIFFBUS  DIFF BUS_0.22UF 6.3V 20% X6S  pkg C0201  page 176 : 1 = P5E_CPU1_PE0_TX_C_DP<3> ; 2 = P5E_CPU1_PE0_TX_DP<3>
C736  Q_CAP_DIFFBUS  DIFF BUS_0.22UF 6.3V 20% X6S  pkg C0201  page 176 : 1 = P5E_CPU1_PE0_TX_C_DN<2> ; 2 = P5E_CPU1_PE0_TX_DN<2>
C737  Q_CAP_DIFFBUS  DIFF BUS_0.22UF 6.3V 20% X6S  pkg C0201  page 176 : 1 = P5E_CPU1_PE0_TX_C_DP<2> ; 2 = P5E_CPU1_PE0_TX_DP<2>
C738  Q_CAP_DIFFBUS  DIFF BUS_0.22UF 6.3V 20% X6S  pkg C0201  page 176 : 1 = P5E_CPU1_PE0_TX_C_DN<1> ; 2 = P5E_CPU1_PE0_TX_DN<1>
C739  Q_CAP_DIFFBUS  DIFF BUS_0.22UF 6.3V 20% X6S  pkg C0201  page 176 : 1 = P5E_CPU1_PE0_TX_C_DP<1> ; 2 = P5E_CPU1_PE0_TX_DP<1>
C740  Q_CAP_DIFFBUS  DIFF BUS_0.22UF 6.3V 20% X6S  pkg C0201  page 176 : 1 = P5E_CPU1_PE0_TX_C_DN<0> ; 2 = P5E_CPU1_PE0_TX_DN<0>
C741  Q_CAP_DIFFBUS  DIFF BUS_0.22UF 6.3V 20% X6S  pkg C0201  page 176 : 1 = P5E_CPU1_PE0_TX_C_DP<0> ; 2 = P5E_CPU1_PE0_TX_DP<0>
C742  Q_CAP_DIFFBUS  DIFF BUS_0.22UF 6.3V 20% X6S  pkg C0201  page 176 : 1 = P5E_CPU1_PE2_TX_C_DN<15> ; 2 = P5E_CPU1_PE2_TX_DN<15>
C743  Q_CAP_DIFFBUS  DIFF BUS_0.22UF 6.3V 20% X6S  pkg C0201  page 176 : 1 = P5E_CPU1_PE2_TX_C_DP<15> ; 2 = P5E_CPU1_PE2_TX_DP<15>
C744  Q_CAP_DIFFBUS  DIFF BUS_0.22UF 6.3V 20% X6S  pkg C0201  page 176 : 1 = P5E_CPU1_PE2_TX_C_DN<14> ; 2 = P5E_CPU1_PE2_TX_DN<14>
C745  Q_CAP_DIFFBUS  DIFF BUS_0.22UF 6.3V 20% X6S  pkg C0201  page 176 : 1 = P5E_CPU1_PE2_TX_C_DP<14> ; 2 = P5E_CPU1_PE2_TX_DP<14>
C746  Q_CAP_DIFFBUS  DIFF BUS_0.22UF 6.3V 20% X6S  pkg C0201  page 176 : 1 = P5E_CPU1_PE2_TX_C_DN<13> ; 2 = P5E_CPU1_PE2_TX_DN<13>
C747  Q_CAP_DIFFBUS  DIFF BUS_0.22UF 6.3V 20% X6S  pkg C0201  page 176 : 1 = P5E_CPU1_PE2_TX_C_DP<13> ; 2 = P5E_CPU1_PE2_TX_DP<13>
C748  Q_CAP_DIFFBUS  DIFF BUS_0.22UF 6.3V 20% X6S  pkg C0201  page 176 : 1 = P5E_CPU1_PE2_TX_C_DN<12> ; 2 = P5E_CPU1_PE2_TX_DN<12>
C749  Q_CAP_DIFFBUS  DIFF BUS_0.22UF 6.3V 20% X6S  pkg C0201  page 176 : 1 = P5E_CPU1_PE2_TX_C_DP<12> ; 2 = P5E_CPU1_PE2_TX_DP<12>
C750  Q_CAP_DIFFBUS  DIFF BUS_0.22UF 6.3V 20% X6S  pkg C0201  page 176 : 1 = P5E_CPU1_PE2_TX_C_DN<11> ; 2 = P5E_CPU1_PE2_TX_DN<11>
C751  Q_CAP_DIFFBUS  DIFF BUS_0.22UF 6.3V 20% X6S  pkg C0201  page 176 : 1 = P5E_CPU1_PE2_TX_C_DP<11> ; 2 = P5E_CPU1_PE2_TX_DP<11>
C752  Q_CAP_DIFFBUS  DIFF BUS_0.22UF 6.3V 20% X6S  pkg C0201  page 176 : 1 = P5E_CPU1_PE2_TX_C_DN<10> ; 2 = P5E_CPU1_PE2_TX_DN<10>
C753  Q_CAP_DIFFBUS  DIFF BUS_0.22UF 6.3V 20% X6S  pkg C0201  page 176 : 1 = P5E_CPU1_PE2_TX_C_DP<10> ; 2 = P5E_CPU1_PE2_TX_DP<10>
C754  Q_CAP_DIFFBUS  DIFF BUS_0.22UF 6.3V 20% X6S  pkg C0201  page 176 : 1 = P5E_CPU1_PE2_TX_C_DN<9> ; 2 = P5E_CPU1_PE2_TX_DN<9>
C755  Q_CAP_DIFFBUS  DIFF BUS_0.22UF 6.3V 20% X6S  pkg C0201  page 176 : 1 = P5E_CPU1_PE2_TX_C_DP<9> ; 2 = P5E_CPU1_PE2_TX_DP<9>
C756  Q_CAP_DIFFBUS  DIFF BUS_0.22UF 6.3V 20% X6S  pkg C0201  page 176 : 1 = P5E_CPU1_PE2_TX_C_DN<8> ; 2 = P5E_CPU1_PE2_TX_DN<8>
C757  Q_CAP_DIFFBUS  DIFF BUS_0.22UF 6.3V 20% X6S  pkg C0201  page 176 : 1 = P5E_CPU1_PE2_TX_C_DP<8> ; 2 = P5E_CPU1_PE2_TX_DP<8>
C758  Q_CAP_DIFFBUS  DIFF BUS_0.22UF 6.3V 20% X6S  pkg C0201  page 176 : 1 = P5E_CPU1_PE2_TX_C_DN<7> ; 2 = P5E_CPU1_PE2_TX_DN<7>
C759  Q_CAP_DIFFBUS  DIFF BUS_0.22UF 6.3V 20% X6S  pkg C0201  page 176 : 1 = P5E_CPU1_PE2_TX_C_DP<7> ; 2 = P5E_CPU1_PE2_TX_DP<7>
C760  Q_CAP_DIFFBUS  DIFF BUS_0.22UF 6.3V 20% X6S  pkg C0201  page 176 : 1 = P5E_CPU1_PE2_TX_C_DN<6> ; 2 = P5E_CPU1_PE2_TX_DN<6>
C761  Q_CAP_DIFFBUS  DIFF BUS_0.22UF 6.3V 20% X6S  pkg C0201  page 176 : 1 = P5E_CPU1_PE2_TX_C_DP<6> ; 2 = P5E_CPU1_PE2_TX_DP<6>
C762  Q_CAP_DIFFBUS  DIFF BUS_0.22UF 6.3V 20% X6S  pkg C0201  page 176 : 1 = P5E_CPU1_PE2_TX_C_DN<5> ; 2 = P5E_CPU1_PE2_TX_DN<5>
C763  Q_CAP_DIFFBUS  DIFF BUS_0.22UF 6.3V 20% X6S  pkg C0201  page 176 : 1 = P5E_CPU1_PE2_TX_C_DP<5> ; 2 = P5E_CPU1_PE2_TX_DP<5>
C764  Q_CAP_DIFFBUS  DIFF BUS_0.22UF 6.3V 20% X6S  pkg C0201  page 176 : 1 = P5E_CPU1_PE2_TX_C_DN<4> ; 2 = P5E_CPU1_PE2_TX_DN<4>
C765  Q_CAP_DIFFBUS  DIFF BUS_0.22UF 6.3V 20% X6S  pkg C0201  page 176 : 1 = P5E_CPU1_PE2_TX_C_DP<4> ; 2 = P5E_CPU1_PE2_TX_DP<4>
C766  Q_CAP_DIFFBUS  DIFF BUS_0.22UF 6.3V 20% X6S  pkg C0201  page 176 : 1 = P5E_CPU1_PE2_TX_C_DN<3> ; 2 = P5E_CPU1_PE2_TX_DN<3>
C767  Q_CAP_DIFFBUS  DIFF BUS_0.22UF 6.3V 20% X6S  pkg C0201  page 176 : 1 = P5E_CPU1_PE2_TX_C_DP<3> ; 2 = P5E_CPU1_PE2_TX_DP<3>
C768  Q_CAP_DIFFBUS  DIFF BUS_0.22UF 6.3V 20% X6S  pkg C0201  page 176 : 1 = P5E_CPU1_PE2_TX_C_DN<2> ; 2 = P5E_CPU1_PE2_TX_DN<2>
C769  Q_CAP_DIFFBUS  DIFF BUS_0.22UF 6.3V 20% X6S  pkg C0201  page 176 : 1 = P5E_CPU1_PE2_TX_C_DP<2> ; 2 = P5E_CPU1_PE2_TX_DP<2>
C770  Q_CAP_DIFFBUS  DIFF BUS_0.22UF 6.3V 20% X6S  pkg C0201  page 176 : 1 = P5E_CPU1_PE2_TX_C_DN<1> ; 2 = P5E_CPU1_PE2_TX_DN<1>
C771  Q_CAP_DIFFBUS  DIFF BUS_0.22UF 6.3V 20% X6S  pkg C0201  page 176 : 1 = P5E_CPU1_PE2_TX_C_DP<1> ; 2 = P5E_CPU1_PE2_TX_DP<1>
C772  Q_CAP_DIFFBUS  DIFF BUS_0.22UF 6.3V 20% X6S  pkg C0201  page 176 : 1 = P5E_CPU1_PE2_TX_C_DN<0> ; 2 = P5E_CPU1_PE2_TX_DN<0>
